# S9S_MB_2U (Grand Teton) — schematic netlist excerpt (pin names and nets, part order shuffled) for the footprints in the layout excerpt that follows; sources: Cadence DE-HDL packaged netlist, KiCad conversion of 03242023_DA0F0TMBIJ0_F0T_Motherboard_J_brd_V01_OCP.brd

Q39  MOSFET_NCH_GDS_ESD_PROTECTED  2N7002K IC  pkg SOT23_GDSXC  page 242
  D  = P12V_SCM_EN
  G  = FM_SCM_PRSNT1_R_N
  S  = GND

(kicad_pcb
	(version 20260206)
	(generator "pcbnew")
	(generator_version "10.0")
	(general
		(thickness 1.6)
		(legacy_teardrops no)
	)
	(paper "A4")
	(title_block
		(title "03242023_DA0F0TMBIJ0_F0T_Motherboard_J_brd_V01_OCP.brd")
		(comment 1 "Grand Teton / footprints 3311-3311 of 6105")
	)
	(layers
		(0 "F.Cu" signal "TOP")
		(4 "In1.Cu" signal "GND")
		(6 "In2.Cu" signal "IN1")
		(8 "In3.Cu" signal "GND1")
		(10 "In4.Cu" signal "IN2")
		(12 "In5.Cu" signal "GND2")
		(14 "In6.Cu" signal "IN3")
		(16 "In7.Cu" signal "GND3")
		(18 "In8.Cu" signal "VCC")
		(20 "In9.Cu" signal "VCC1")
		(22 "In10.Cu" signal "GND4")
		(24 "In11.Cu" signal "IN4")
		(26 "In12.Cu" signal "GND5")
		(28 "In13.Cu" signal "IN5")
		(30 "In14.Cu" signal "GND6")
		(32 "In15.Cu" signal "IN6")
		(34 "In16.Cu" signal "GND7")
		(2 "B.Cu" signal "BOTTOM")
		(9 "F.Adhes" user "F.Adhesive")
		(11 "B.Adhes" user "B.Adhesive")
		(13 "F.Paste" user "Package Geometry/Pastemask Top")
		(15 "B.Paste" user "Package Geometry/Pastemask Bottom")
		(5 "F.SilkS" user "Ref Des/Silkscreen Top")
		(7 "B.SilkS" user "Ref Des/Silkscreen Bottom")
		(1 "F.Mask" user "Board Geometry/Soldermask Top")
		(3 "B.Mask" user "Board Geometry/Soldermask Bottom")
		(17 "Dwgs.User" user "User.Drawings")
		(19 "Cmts.User" user "User.Comments")
		(21 "Eco1.User" user "User.Eco1")
		(23 "Eco2.User" user "User.Eco2")
		(25 "Edge.Cuts" user "Board Geometry/Outline")
		(27 "Margin" user)
		(31 "F.CrtYd" user "Package Geometry/Place Bound Top")
		(29 "B.CrtYd" user "Package Geometry/Place Bound Bottom")
		(35 "F.Fab" user "Ref Des/Assembly Top")
		(33 "B.Fab" user "Ref Des/Assembly Bottom")
	)
	(footprint ""
		(layer "F.Cu")
		(at 193.809366 -37.43325 90)
		(property "Reference" "Q39"
			(at -2.314702 -0.629158 0)
			(unlocked yes)
			(layer "F.SilkS")
			(effects
				(font
					(size 0.7874 0.5842)
					(thickness 0.1524)
				)
			)
		)
		(property "Value" ""
			(at 0 0 90)
			(layer "F.Fab")
			(effects
				(font
					(size 1.27 1.27)
				)
			)
		)
		(duplicate_pad_numbers_are_jumpers no)
		(fp_line
			(start 1.603248 -1.500124)
			(end 1.603248 1.500124)
			(stroke
				(width 0.1524)
				(type default)
			)
			(layer "F.SilkS")
		)
		(fp_line
			(start -1.603248 -1.500124)
			(end 1.603248 -1.500124)
			(stroke
				(width 0.1524)
				(type default)
			)
			(layer "F.SilkS")
		)
		(fp_line
			(start 1.603248 1.500124)
			(end -1.603248 1.500124)
			(stroke
				(width 0.1524)
				(type default)
			)
			(layer "F.SilkS")
		)
		(fp_line
			(start -1.603248 1.500124)
			(end -1.603248 -1.500124)
			(stroke
				(width 0.1524)
				(type default)
			)
			(layer "F.SilkS")
		)
		(fp_line
			(start 0.700024 -1.500124)
			(end -0.700024 -1.500124)
			(stroke
				(width 0.1)
				(type default)
			)
			(layer "F.Fab")
		)
		(fp_line
			(start -0.700024 -1.500124)
			(end -0.700024 -1.169924)
			(stroke
				(width 0.1)
				(type default)
			)
			(layer "F.Fab")
		)
		(fp_line
			(start -0.700024 -1.169924)
			(end -1.249934 -1.169924)
			(stroke
				(width 0.1)
				(type default)
			)
			(layer "F.Fab")
		)
		(fp_line
			(start -1.249934 -1.169924)
			(end -1.249934 -0.729996)
			(stroke
				(width 0.1)
				(type default)
			)
			(layer "F.Fab")
		)
		(fp_line
			(start -0.6985 -0.729996)
			(end -0.6985 0.729996)
			(stroke
				(width 0.1)
				(type default)
			)
			(layer "F.Fab")
		)
		(fp_line
			(start -1.249934 -0.729996)
			(end -0.6985 -0.729996)
			(stroke
				(width 0.1)
				(type default)
			)
			(layer "F.Fab")
		)
		(fp_line
			(start 1.249934 -0.219964)
			(end 0.700024 -0.219964)
			(stroke
				(width 0.1)
				(type default)
			)
			(layer "F.Fab")
		)
		(fp_line
			(start 0.700024 -0.219964)
			(end 0.700024 -1.500124)
			(stroke
				(width 0.1)
				(type default)
			)
			(layer "F.Fab")
		)
		(fp_line
			(start 1.249934 0.219964)
			(end 1.249934 -0.219964)
			(stroke
				(width 0.1)
				(type default)
			)
			(layer "F.Fab")
		)
		(fp_line
			(start 0.700024 0.219964)
			(end 1.249934 0.219964)
			(stroke
				(width 0.1)
				(type default)
			)
			(layer "F.Fab")
		)
		(fp_line
			(start -0.6985 0.729996)
			(end -1.249934 0.729996)
			(stroke
				(width 0.1)
				(type default)
			)
			(layer "F.Fab")
		)
		(fp_line
			(start -1.249934 0.729996)
			(end -1.249934 1.169924)
			(stroke
				(width 0.1)
				(type default)
			)
			(layer "F.Fab")
		)
		(fp_line
			(start -0.700024 1.169924)
			(end -0.700024 1.500124)
			(stroke
				(width 0.1)
				(type default)
			)
			(layer "F.Fab")
		)
		(fp_line
			(start -1.249934 1.169924)
			(end -0.700024 1.169924)
			(stroke
				(width 0.1)
				(type default)
			)
			(layer "F.Fab")
		)
		(fp_line
			(start 0.700024 1.500124)
			(end 0.700024 0.219964)
			(stroke
				(width 0.1)
				(type default)
			)
			(layer "F.Fab")
		)
		(fp_line
			(start -0.700024 1.500124)
			(end 0.700024 1.500124)
			(stroke
				(width 0.1)
				(type default)
			)
			(layer "F.Fab")
		)
		(fp_rect
			(start -0.700024 -1.500124)
			(end 0.700024 1.500124)
			(stroke
				(width 0)
				(type default)
			)
			(fill no)
			(layer "F.Fab")
		)
		(pad "D" smd rect
			(at 0.999998 0)
			(size 0.8128 0.9144)
			(layers "F.Cu" "F.Mask" "F.Paste")
			(net "P12V_SCM_EN")
		)
		(pad "G" smd rect
			(at -0.999998 -0.94996)
			(size 0.8128 0.9144)
			(layers "F.Cu" "F.Mask" "F.Paste")
			(net "FM_SCM_PRSNT1_R_N")
		)
		(pad "S" smd rect
			(at -0.999998 0.94996)
			(size 0.8128 0.9144)
			(layers "F.Cu" "F.Mask" "F.Paste")
			(net "GND")
		)
	)
)
